# S9S_MB_2U (Grand Teton) — schematic netlist excerpt (pin names and nets, part order shuffled) for the footprints in the layout excerpt that follows; sources: Cadence DE-HDL packaged netlist, KiCad conversion of 03242023_DA0F0TMBIJ0_F0T_Motherboard_J_brd_V01_OCP.brd

R3764  Q_RES  4.7K 1% EMPTY  pkg 0402LF  page 171 : A = GND ; B = INA230_2_A0
R4621  Q_RES  33.2 1% CHIP  pkg 0402LF  page 226 : A = H_CPU_CATERR_LVC2_BMC_R_N ; B = H_CPU_CATERR_LVC2_BMC_N

(kicad_pcb
	(version 20260206)
	(generator "pcbnew")
	(generator_version "10.0")
	(general
		(thickness 1.6)
		(legacy_teardrops no)
	)
	(paper "A4")
	(title_block
		(title "03242023_DA0F0TMBIJ0_F0T_Motherboard_J_brd_V01_OCP.brd")
		(comment 1 "Grand Teton / footprints 5932-5933 of 6105")
	)
	(layers
		(0 "F.Cu" signal "TOP")
		(4 "In1.Cu" signal "GND")
		(6 "In2.Cu" signal "IN1")
		(8 "In3.Cu" signal "GND1")
		(10 "In4.Cu" signal "IN2")
		(12 "In5.Cu" signal "GND2")
		(14 "In6.Cu" signal "IN3")
		(16 "In7.Cu" signal "GND3")
		(18 "In8.Cu" signal "VCC")
		(20 "In9.Cu" signal "VCC1")
		(22 "In10.Cu" signal "GND4")
		(24 "In11.Cu" signal "IN4")
		(26 "In12.Cu" signal "GND5")
		(28 "In13.Cu" signal "IN5")
		(30 "In14.Cu" signal "GND6")
		(32 "In15.Cu" signal "IN6")
		(34 "In16.Cu" signal "GND7")
		(2 "B.Cu" signal "BOTTOM")
		(9 "F.Adhes" user "F.Adhesive")
		(11 "B.Adhes" user "B.Adhesive")
		(13 "F.Paste" user "Package Geometry/Pastemask Top")
		(15 "B.Paste" user "Package Geometry/Pastemask Bottom")
		(5 "F.SilkS" user "Ref Des/Silkscreen Top")
		(7 "B.SilkS" user "Ref Des/Silkscreen Bottom")
		(1 "F.Mask" user "Board Geometry/Soldermask Top")
		(3 "B.Mask" user "Board Geometry/Soldermask Bottom")
		(17 "Dwgs.User" user "User.Drawings")
		(19 "Cmts.User" user "User.Comments")
		(21 "Eco1.User" user "User.Eco1")
		(23 "Eco2.User" user "User.Eco2")
		(25 "Edge.Cuts" user "Board Geometry/Outline")
		(27 "Margin" user)
		(31 "F.CrtYd" user "Package Geometry/Place Bound Top")
		(29 "B.CrtYd" user "Package Geometry/Place Bound Bottom")
		(35 "F.Fab" user "Ref Des/Assembly Top")
		(33 "B.Fab" user "Ref Des/Assembly Bottom")
	)
	(footprint ""
		(layer "B.Cu")
		(at 214.43188 -55.971948)
		(property "Reference" "R3764"
			(at 0 0 0)
			(layer "B.SilkS")
			(hide yes)
			(effects
				(font
					(size 1.27 1.27)
				)
				(justify mirror)
			)
		)
		(property "Value" ""
			(at 0 0 0)
			(layer "B.Fab")
			(effects
				(font
					(size 1.27 1.27)
				)
				(justify mirror)
			)
		)
		(duplicate_pad_numbers_are_jumpers no)
		(fp_line
			(start -0.7874 -0.4064)
			(end -0.7874 0.4064)
			(stroke
				(width 0.1524)
				(type default)
			)
			(layer "B.SilkS")
		)
		(fp_line
			(start -0.7874 0.4064)
			(end 0.7874 0.4064)
			(stroke
				(width 0.1524)
				(type default)
			)
			(layer "B.SilkS")
		)
		(fp_line
			(start 0.7874 -0.4064)
			(end -0.7874 -0.4064)
			(stroke
				(width 0.1524)
				(type default)
			)
			(layer "B.SilkS")
		)
		(fp_line
			(start 0.7874 0.4064)
			(end 0.7874 -0.4064)
			(stroke
				(width 0.1524)
				(type default)
			)
			(layer "B.SilkS")
		)
		(fp_line
			(start -0.67945 -0.3048)
			(end -0.67945 0.3048)
			(stroke
				(width 0.1)
				(type default)
			)
			(layer "B.Fab")
		)
		(fp_line
			(start -0.67945 0.3048)
			(end -0.120396 0.3048)
			(stroke
				(width 0.1)
				(type default)
			)
			(layer "B.Fab")
		)
		(fp_line
			(start -0.12065 -0.3048)
			(end -0.67945 -0.3048)
			(stroke
				(width 0.1)
				(type default)
			)
			(layer "B.Fab")
		)
		(fp_line
			(start -0.12065 -0.2794)
			(end -0.12065 -0.3048)
			(stroke
				(width 0.1)
				(type default)
			)
			(layer "B.Fab")
		)
		(fp_line
			(start -0.120396 0.2794)
			(end 0.12065 0.2794)
			(stroke
				(width 0.1)
				(type default)
			)
			(layer "B.Fab")
		)
		(fp_line
			(start -0.120396 0.3048)
			(end -0.120396 0.2794)
			(stroke
				(width 0.1)
				(type default)
			)
			(layer "B.Fab")
		)
		(fp_line
			(start 0.12065 -0.305054)
			(end 0.12065 -0.2794)
			(stroke
				(width 0.1)
				(type default)
			)
			(layer "B.Fab")
		)
		(fp_line
			(start 0.12065 -0.2794)
			(end -0.12065 -0.2794)
			(stroke
				(width 0.1)
				(type default)
			)
			(layer "B.Fab")
		)
		(fp_line
			(start 0.12065 0.2794)
			(end 0.12065 0.3048)
			(stroke
				(width 0.1)
				(type default)
			)
			(layer "B.Fab")
		)
		(fp_line
			(start 0.12065 0.3048)
			(end 0.67945 0.3048)
			(stroke
				(width 0.1)
				(type default)
			)
			(layer "B.Fab")
		)
		(fp_line
			(start 0.67945 -0.305054)
			(end 0.12065 -0.305054)
			(stroke
				(width 0.1)
				(type default)
			)
			(layer "B.Fab")
		)
		(fp_line
			(start 0.67945 0.3048)
			(end 0.67945 -0.305054)
			(stroke
				(width 0.1)
				(type default)
			)
			(layer "B.Fab")
		)
		(pad "1" smd circle
			(at 0.40005 0 180)
			(size 0 0)
			(layers "B.Cu" "B.Mask" "B.Paste")
			(net "GND")
		)
		(pad "2" smd circle
			(at -0.40005 0 180)
			(size 0 0)
			(layers "B.Cu" "B.Mask" "B.Paste")
			(net "INA230_2_A0")
		)
	)
	(footprint ""
		(layer "B.Cu")
		(at 117.0432 -96.916748 -90)
		(property "Reference" "R4621"
			(at 0 0 90)
			(layer "B.SilkS")
			(hide yes)
			(effects
				(font
					(size 1.27 1.27)
				)
				(justify mirror)
			)
		)
		(property "Value" ""
			(at 0 0 90)
			(layer "B.Fab")
			(effects
				(font
					(size 1.27 1.27)
				)
				(justify mirror)
			)
		)
		(duplicate_pad_numbers_are_jumpers no)
		(fp_line
			(start -0.7874 0.4064)
			(end 0.7874 0.4064)
			(stroke
				(width 0.1524)
				(type default)
			)
			(layer "B.SilkS")
		)
		(fp_line
			(start 0.7874 0.4064)
			(end 0.7874 -0.4064)
			(stroke
				(width 0.1524)
				(type default)
			)
			(layer "B.SilkS")
		)
		(fp_line
			(start -0.7874 -0.4064)
			(end -0.7874 0.4064)
			(stroke
				(width 0.1524)
				(type default)
			)
			(layer "B.SilkS")
		)
		(fp_line
			(start 0.7874 -0.4064)
			(end -0.7874 -0.4064)
			(stroke
				(width 0.1524)
				(type default)
			)
			(layer "B.SilkS")
		)
		(fp_line
			(start -0.67945 0.3048)
			(end -0.120396 0.3048)
			(stroke
				(width 0.1)
				(type default)
			)
			(layer "B.Fab")
		)
		(fp_line
			(start -0.120396 0.3048)
			(end -0.120396 0.2794)
			(stroke
				(width 0.1)
				(type default)
			)
			(layer "B.Fab")
		)
		(fp_line
			(start 0.12065 0.3048)
			(end 0.67945 0.3048)
			(stroke
				(width 0.1)
				(type default)
			)
			(layer "B.Fab")
		)
		(fp_line
			(start 0.67945 0.3048)
			(end 0.67945 -0.305054)
			(stroke
				(width 0.1)
				(type default)
			)
			(layer "B.Fab")
		)
		(fp_line
			(start -0.120396 0.2794)
			(end 0.12065 0.2794)
			(stroke
				(width 0.1)
				(type default)
			)
			(layer "B.Fab")
		)
		(fp_line
			(start 0.12065 0.2794)
			(end 0.12065 0.3048)
			(stroke
				(width 0.1)
				(type default)
			)
			(layer "B.Fab")
		)
		(fp_line
			(start -0.12065 -0.2794)
			(end -0.12065 -0.3048)
			(stroke
				(width 0.1)
				(type default)
			)
			(layer "B.Fab")
		)
		(fp_line
			(start 0.12065 -0.2794)
			(end -0.12065 -0.2794)
			(stroke
				(width 0.1)
				(type default)
			)
			(layer "B.Fab")
		)
		(fp_line
			(start -0.67945 -0.3048)
			(end -0.67945 0.3048)
			(stroke
				(width 0.1)
				(type default)
			)
			(layer "B.Fab")
		)
		(fp_line
			(start -0.12065 -0.3048)
			(end -0.67945 -0.3048)
			(stroke
				(width 0.1)
				(type default)
			)
			(layer "B.Fab")
		)
		(fp_line
			(start 0.12065 -0.305054)
			(end 0.12065 -0.2794)
			(stroke
				(width 0.1)
				(type default)
			)
			(layer "B.Fab")
		)
		(fp_line
			(start 0.67945 -0.305054)
			(end 0.12065 -0.305054)
			(stroke
				(width 0.1)
				(type default)
			)
			(layer "B.Fab")
		)
		(pad "1" smd circle
			(at 0.40005 0 90)
			(size 0 0)
			(layers "B.Cu" "B.Mask" "B.Paste")
			(net "H_CPU_CATERR_LVC2_BMC_R_N")
		)
		(pad "2" smd circle
			(at -0.40005 0 90)
			(size 0 0)
			(layers "B.Cu" "B.Mask" "B.Paste")
			(net "H_CPU_CATERR_LVC2_BMC_N")
		)
	)
)
